FILE_TYPE = MACRO_DRAWING;
SET COLOR_WIRE YELLOW;
SET COLOR_PROP ORANGE;
SET COLOR_DOT WHITE;
SET COLOR_ARC YELLOW;
SET COLOR_BODY GREEN;
SET COLOR_NOTE PURPLE;
SET PROP_DISPLAY VALUE;
SET PAGE_NUMBER P362;
FORCEADD QUANTA_TITLE_BLOCK_C..1
(4475 -3475);
FORCEPROP 1 LAST Q_TITLE Blank
J 0
(-4866 -3424);
DISPLAY 2.446809 (-4866 -3424);
PAINT GREEN (-4866 -3424);
FORCEPROP 2 LAST CUSTOM_TXT_CDS <CON_LAST_MODIFIED>
J 0
(2590 -3460);
DISPLAY 0.978723 (2590 -3460);
FORCEPROP 2 LAST CUSTOM_TXT_CDS <NAME_2>
J 0
(1300 -3425);
FORCEPROP 2 LAST CUSTOM_TXT_CDS <NAME_1>
J 0
(1300 -3300);
FORCEPROP 2 LAST CUSTOM_TXT_CDS <Q_NUMBER>
J 0
(3072 -3372);
DISPLAY 1.212766 (3072 -3372);
FORCEPROP 2 LAST CUSTOM_TXT_CDS <Q_PROJ>
J 0
(2093 -3373);
DISPLAY 1.212766 (2093 -3373);
FORCEPROP 2 LAST CUSTOM_TXT_CDS <Q_REV>
J 0
(4291 -3372);
DISPLAY 1.212766 (4291 -3372);
FORCEPROP 2 LAST CUSTOM_TXT_CDS <CON_PAGE_NUM> OF <CON_TOTAL_PAGES>
J 0
(4029 -3457);
DISPLAY 0.978723 (4029 -3457);
FORCEPROP 2 LAST CDS_LIB pure_quanta
J 0
(4475 -3475);
DISPLAY INVISIBLE (4475 -3475);
FORCEPROP 1 LAST CDS_LMAN_SYM_OUTLINE -9475,6775,100,-125
J 0
(4475 -3475);
DISPLAY 0.468085 (4475 -3475);
PAINT GREEN (4475 -3475);
DISPLAY INVISIBLE (4475 -3475);
FORCEPROP 2 LAST PAGE_BORDER TRUE
J 0
(-3415 1775);
DISPLAY 0.638298 (-3415 1775);
PAINT PINK (-3415 1775);
DISPLAY INVISIBLE (-3415 1775);
FORCEPROP 2 LAST CDS_XR_PAGE_TITLE CR-240 : @T6G_MB_LIB.T6G(SCH_1):PAGE240
J 0
(-3415 1775);
DISPLAY 0.638298 (-3415 1775);
PAINT PINK (-3415 1775);
DISPLAY INVISIBLE (-3415 1775);
FORCEPROP 2 LAST CUSTOM_TXT_CDS <XR_PAGE_TITLE>
J 0
(-3415 1775);
DISPLAY 0.638298 (-3415 1775);
PAINT PINK (-3415 1775);
DISPLAY INVISIBLE (-3415 1775);
FORCEPROP 1 LAST COMMENT_BODY TRUE
J 0
(4487 -3488);
DISPLAY 0.978723 (4487 -3488);
PAINT GREEN (4487 -3488);
DISPLAY INVISIBLE (4487 -3488);
FORCEPROP 1 LAST Q_DEPT BU9
J 1
(712 -3426);
DISPLAY 1.957447 (712 -3426);
PAINT GREEN (712 -3426);
DISPLAY INVISIBLE (712 -3426);
FORCEPROP 0 LAST CDS_CON_LAST_MODIFIED Thu Aug 24 10:15:37 2023
J 0
(2590 -3460);
DISPLAY INVISIBLE (2590 -3460);
QUIT
